(kicad_pcb
	(version 20260206)
	(generator "pcbnew")
	(generator_version "10.0")
	(general
		(thickness 1.6)
		(legacy_teardrops no)
	)
	(paper "A4")
	(title_block
		(title "04192023_DAF0TMB3IC0_F0TG_MB_C_brd_V02_OCP.brd")
		(comment 1 "Grand Teton / footprints 6560-6565 of 8354")
	)
	(layers
		(0 "F.Cu" signal "TOP")
		(4 "In1.Cu" signal "GND")
		(6 "In2.Cu" signal "IN1")
		(8 "In3.Cu" signal "GND1")
		(10 "In4.Cu" signal "IN2")
		(12 "In5.Cu" signal "GND2")
		(14 "In6.Cu" signal "IN3")
		(16 "In7.Cu" signal "GND3")
		(18 "In8.Cu" signal "VCC")
		(20 "In9.Cu" signal "VCC1")
		(22 "In10.Cu" signal "GND4")
		(24 "In11.Cu" signal "IN4")
		(26 "In12.Cu" signal "GND5")
		(28 "In13.Cu" signal "IN5")
		(30 "In14.Cu" signal "GND6")
		(32 "In15.Cu" signal "IN6")
		(34 "In16.Cu" signal "GND7")
		(2 "B.Cu" signal "BOTTOM")
		(9 "F.Adhes" user "F.Adhesive")
		(11 "B.Adhes" user "B.Adhesive")
		(13 "F.Paste" user "Package Geometry/Pastemask Top")
		(15 "B.Paste" user "Package Geometry/Pastemask Bottom")
		(5 "F.SilkS" user "Ref Des/Silkscreen Top")
		(7 "B.SilkS" user "Ref Des/Silkscreen Bottom")
		(1 "F.Mask" user "Board Geometry/Soldermask Top")
		(3 "B.Mask" user "Board Geometry/Soldermask Bottom")
		(17 "Dwgs.User" user "User.Drawings")
		(19 "Cmts.User" user "User.Comments")
		(21 "Eco1.User" user "User.Eco1")
		(23 "Eco2.User" user "User.Eco2")
		(25 "Edge.Cuts" user "Board Geometry/Outline")
		(27 "Margin" user)
		(31 "F.CrtYd" user "Package Geometry/Place Bound Top")
		(29 "B.CrtYd" user "Package Geometry/Place Bound Bottom")
		(35 "F.Fab" user "Ref Des/Assembly Top")
		(33 "B.Fab" user "Ref Des/Assembly Bottom")
	)
	(footprint ""
		(layer "B.Cu")
		(at 110.177834 -248.916952 120)
		(property "Reference" "C2347"
			(at 0 0 120)
			(layer "B.SilkS")
			(hide yes)
			(effects
				(font
					(size 1.27 1.27)
				)
				(justify mirror)
			)
		)
		(property "Value" ""
			(at 0 0 120)
			(layer "B.Fab")
			(effects
				(font
					(size 1.27 1.27)
				)
				(justify mirror)
			)
		)
		(duplicate_pad_numbers_are_jumpers no)
		(fp_line
			(start 0.787516 -0.406438)
			(end -0.787425 -0.40652)
			(stroke
				(width 0.1524)
				(type default)
			)
			(layer "B.SilkS")
		)
		(fp_line
			(start 0.787425 0.40652)
			(end 0.787516 -0.406438)
			(stroke
				(width 0.1524)
				(type default)
			)
			(layer "B.SilkS")
		)
		(fp_line
			(start -0.787425 -0.40652)
			(end -0.787516 0.406438)
			(stroke
				(width 0.1524)
				(type default)
			)
			(layer "B.SilkS")
		)
		(fp_line
			(start -0.787516 0.406438)
			(end 0.787425 0.40652)
			(stroke
				(width 0.1524)
				(type default)
			)
			(layer "B.SilkS")
		)
		(fp_line
			(start 0.679475 -0.305158)
			(end 0.120732 -0.305125)
			(stroke
				(width 0.1)
				(type default)
			)
			(layer "B.Fab")
		)
		(fp_line
			(start 0.120732 -0.305125)
			(end 0.120554 -0.279418)
			(stroke
				(width 0.1)
				(type default)
			)
			(layer "B.Fab")
		)
		(fp_line
			(start 0.120554 -0.279418)
			(end -0.120587 -0.279326)
			(stroke
				(width 0.1)
				(type default)
			)
			(layer "B.Fab")
		)
		(fp_line
			(start -0.120536 -0.304813)
			(end -0.6795 -0.304908)
			(stroke
				(width 0.1)
				(type default)
			)
			(layer "B.Fab")
		)
		(fp_line
			(start -0.120587 -0.279326)
			(end -0.120536 -0.304813)
			(stroke
				(width 0.1)
				(type default)
			)
			(layer "B.Fab")
		)
		(fp_line
			(start 0.6795 0.304908)
			(end 0.679475 -0.305158)
			(stroke
				(width 0.1)
				(type default)
			)
			(layer "B.Fab")
		)
		(fp_line
			(start -0.6795 -0.304908)
			(end -0.679568 0.304811)
			(stroke
				(width 0.1)
				(type default)
			)
			(layer "B.Fab")
		)
		(fp_line
			(start 0.120587 0.279326)
			(end 0.120536 0.304813)
			(stroke
				(width 0.1)
				(type default)
			)
			(layer "B.Fab")
		)
		(fp_line
			(start 0.120536 0.304813)
			(end 0.6795 0.304908)
			(stroke
				(width 0.1)
				(type default)
			)
			(layer "B.Fab")
		)
		(fp_line
			(start -0.120334 0.279545)
			(end 0.120587 0.279326)
			(stroke
				(width 0.1)
				(type default)
			)
			(layer "B.Fab")
		)
		(fp_line
			(start -0.120258 0.304812)
			(end -0.120334 0.279545)
			(stroke
				(width 0.1)
				(type default)
			)
			(layer "B.Fab")
		)
		(fp_line
			(start -0.679568 0.304811)
			(end -0.120258 0.304812)
			(stroke
				(width 0.1)
				(type default)
			)
			(layer "B.Fab")
		)
		(pad "1" smd circle
			(at 0.40005 0 300)
			(size 0 0)
			(layers "B.Cu" "B.Mask" "B.Paste")
			(net "PVDDCR_CPU0_P1")
		)
		(pad "2" smd circle
			(at -0.40005 0 300)
			(size 0 0)
			(layers "B.Cu" "B.Mask" "B.Paste")
			(net "GND")
		)
	)
	(footprint ""
		(layer "B.Cu")
		(at 155.364434 -199.234552 -90)
		(property "Reference" "C231"
			(at 0 0 90)
			(layer "B.SilkS")
			(hide yes)
			(effects
				(font
					(size 1.27 1.27)
				)
				(justify mirror)
			)
		)
		(property "Value" ""
			(at 0 0 90)
			(layer "B.Fab")
			(effects
				(font
					(size 1.27 1.27)
				)
				(justify mirror)
			)
		)
		(duplicate_pad_numbers_are_jumpers no)
		(fp_line
			(start -0.7874 0.4064)
			(end 0.7874 0.4064)
			(stroke
				(width 0.1524)
				(type default)
			)
			(layer "B.SilkS")
		)
		(fp_line
			(start 0.7874 0.4064)
			(end 0.7874 -0.4064)
			(stroke
				(width 0.1524)
				(type default)
			)
			(layer "B.SilkS")
		)
		(fp_line
			(start -0.7874 -0.4064)
			(end -0.7874 0.4064)
			(stroke
				(width 0.1524)
				(type default)
			)
			(layer "B.SilkS")
		)
		(fp_line
			(start 0.7874 -0.4064)
			(end -0.7874 -0.4064)
			(stroke
				(width 0.1524)
				(type default)
			)
			(layer "B.SilkS")
		)
		(fp_line
			(start -0.67945 0.3048)
			(end -0.120396 0.3048)
			(stroke
				(width 0.1)
				(type default)
			)
			(layer "B.Fab")
		)
		(fp_line
			(start -0.120396 0.3048)
			(end -0.120396 0.2794)
			(stroke
				(width 0.1)
				(type default)
			)
			(layer "B.Fab")
		)
		(fp_line
			(start 0.12065 0.3048)
			(end 0.67945 0.3048)
			(stroke
				(width 0.1)
				(type default)
			)
			(layer "B.Fab")
		)
		(fp_line
			(start 0.67945 0.3048)
			(end 0.67945 -0.305054)
			(stroke
				(width 0.1)
				(type default)
			)
			(layer "B.Fab")
		)
		(fp_line
			(start -0.120396 0.2794)
			(end 0.12065 0.2794)
			(stroke
				(width 0.1)
				(type default)
			)
			(layer "B.Fab")
		)
		(fp_line
			(start 0.12065 0.2794)
			(end 0.12065 0.3048)
			(stroke
				(width 0.1)
				(type default)
			)
			(layer "B.Fab")
		)
		(fp_line
			(start -0.12065 -0.2794)
			(end -0.12065 -0.3048)
			(stroke
				(width 0.1)
				(type default)
			)
			(layer "B.Fab")
		)
		(fp_line
			(start 0.12065 -0.2794)
			(end -0.12065 -0.2794)
			(stroke
				(width 0.1)
				(type default)
			)
			(layer "B.Fab")
		)
		(fp_line
			(start -0.67945 -0.3048)
			(end -0.67945 0.3048)
			(stroke
				(width 0.1)
				(type default)
			)
			(layer "B.Fab")
		)
		(fp_line
			(start -0.12065 -0.3048)
			(end -0.67945 -0.3048)
			(stroke
				(width 0.1)
				(type default)
			)
			(layer "B.Fab")
		)
		(fp_line
			(start 0.12065 -0.305054)
			(end 0.12065 -0.2794)
			(stroke
				(width 0.1)
				(type default)
			)
			(layer "B.Fab")
		)
		(fp_line
			(start 0.67945 -0.305054)
			(end 0.12065 -0.305054)
			(stroke
				(width 0.1)
				(type default)
			)
			(layer "B.Fab")
		)
		(pad "1" smd circle
			(at 0.40005 0 90)
			(size 0 0)
			(layers "B.Cu" "B.Mask" "B.Paste")
			(net "JTAG_CPU1_TDI")
		)
		(pad "2" smd circle
			(at -0.40005 0 90)
			(size 0 0)
			(layers "B.Cu" "B.Mask" "B.Paste")
			(net "GND")
		)
	)
	(footprint ""
		(layer "B.Cu")
		(at 328.400664 -73.534778)
		(property "Reference" "Q80"
			(at 0.95885 -1.724152 0)
			(unlocked yes)
			(layer "B.SilkS")
			(effects
				(font
					(size 0.7874 0.5842)
					(thickness 0.1524)
				)
				(justify left mirror)
			)
		)
		(property "Value" ""
			(at 0 0 0)
			(layer "B.Fab")
			(effects
				(font
					(size 1.27 1.27)
				)
				(justify mirror)
			)
		)
		(duplicate_pad_numbers_are_jumpers no)
		(fp_line
			(start -1.332738 -1.100074)
			(end -1.332738 1.100074)
			(stroke
				(width 0.1524)
				(type default)
			)
			(layer "B.SilkS")
		)
		(fp_line
			(start -1.332738 1.100074)
			(end 1.332738 1.100074)
			(stroke
				(width 0.1524)
				(type default)
			)
			(layer "B.SilkS")
		)
		(fp_line
			(start -0.4826 -1.100074)
			(end -1.332738 -1.100074)
			(stroke
				(width 0.1524)
				(type default)
			)
			(layer "B.SilkS")
		)
		(fp_line
			(start 0 -0.541274)
			(end -0.4826 -1.100074)
			(stroke
				(width 0.1524)
				(type default)
			)
			(layer "B.SilkS")
		)
		(fp_line
			(start 0.4826 -1.100074)
			(end 0 -0.541274)
			(stroke
				(width 0.1524)
				(type default)
			)
			(layer "B.SilkS")
		)
		(fp_line
			(start 1.332738 -1.100074)
			(end 0.4826 -1.100074)
			(stroke
				(width 0.1524)
				(type default)
			)
			(layer "B.SilkS")
		)
		(fp_line
			(start 1.332738 1.100074)
			(end 1.332738 -1.100074)
			(stroke
				(width 0.1524)
				(type default)
			)
			(layer "B.SilkS")
		)
		(fp_poly
			(pts
				(xy 1.367536 -0.649986) (xy 2.069592 -1.001014) (xy 2.069592 -0.298958)
			)
			(stroke
				(width 0)
				(type default)
			)
			(fill yes)
			(layer "B.SilkS")
		)
		(fp_line
			(start -0.674878 -1.100074)
			(end -0.674878 1.100074)
			(stroke
				(width 0.1)
				(type default)
			)
			(layer "B.Fab")
		)
		(fp_line
			(start -0.674878 1.100074)
			(end 0.674878 1.100074)
			(stroke
				(width 0.1)
				(type default)
			)
			(layer "B.Fab")
		)
		(fp_line
			(start 0.674878 -1.100074)
			(end -0.674878 -1.100074)
			(stroke
				(width 0.1)
				(type default)
			)
			(layer "B.Fab")
		)
		(fp_line
			(start 0.674878 1.100074)
			(end 0.674878 -1.100074)
			(stroke
				(width 0.1)
				(type default)
			)
			(layer "B.Fab")
		)
		(fp_poly
			(pts
				(xy 2.2352 -0.298958) (xy 2.2352 -1.001014) (xy 1.533144 -0.649986)
			)
			(stroke
				(width 0)
				(type default)
			)
			(fill yes)
			(layer "B.Fab")
		)
		(pad "1" smd rect
			(at 0.94996 -0.649986 90)
			(size 0.4318 0.508)
			(layers "B.Cu" "B.Mask" "B.Paste")
			(net "GND")
		)
		(pad "2" smd rect
			(at 0.94996 0 90)
			(size 0.4318 0.508)
			(layers "B.Cu" "B.Mask" "B.Paste")
			(net "FM_LED_PWRGD_PVDDCR_SOC_P0")
		)
		(pad "3" smd rect
			(at 0.94996 0.649986 90)
			(size 0.4318 0.508)
			(layers "B.Cu" "B.Mask" "B.Paste")
			(net "LED_PWRGD_PVDDCR_CPU1_P0_D")
		)
		(pad "4" smd rect
			(at -0.94996 0.649986 90)
			(size 0.4318 0.508)
			(layers "B.Cu" "B.Mask" "B.Paste")
			(net "GND")
		)
		(pad "5" smd rect
			(at -0.94996 0 90)
			(size 0.4318 0.508)
			(layers "B.Cu" "B.Mask" "B.Paste")
			(net "FM_LED_PWRGD_PVDDCR_CPU1_P0")
		)
		(pad "6" smd rect
			(at -0.94996 -0.649986 90)
			(size 0.4318 0.508)
			(layers "B.Cu" "B.Mask" "B.Paste")
			(net "LED_PWRGD_PVDDCR_SOC_P0_D")
		)
	)
	(footprint ""
		(layer "B.Cu")
		(at 117.895624 -260.305296)
		(property "Reference" "C2463"
			(at 0 0 0)
			(layer "B.SilkS")
			(hide yes)
			(effects
				(font
					(size 1.27 1.27)
				)
				(justify mirror)
			)
		)
		(property "Value" ""
			(at 0 0 0)
			(layer "B.Fab")
			(effects
				(font
					(size 1.27 1.27)
				)
				(justify mirror)
			)
		)
		(duplicate_pad_numbers_are_jumpers no)
		(fp_line
			(start -0.7874 -0.4064)
			(end -0.7874 0.4064)
			(stroke
				(width 0.1524)
				(type default)
			)
			(layer "B.SilkS")
		)
		(fp_line
			(start -0.7874 0.4064)
			(end 0.7874 0.4064)
			(stroke
				(width 0.1524)
				(type default)
			)
			(layer "B.SilkS")
		)
		(fp_line
			(start 0.7874 -0.4064)
			(end -0.7874 -0.4064)
			(stroke
				(width 0.1524)
				(type default)
			)
			(layer "B.SilkS")
		)
		(fp_line
			(start 0.7874 0.4064)
			(end 0.7874 -0.4064)
			(stroke
				(width 0.1524)
				(type default)
			)
			(layer "B.SilkS")
		)
		(fp_line
			(start -0.67945 -0.3048)
			(end -0.67945 0.3048)
			(stroke
				(width 0.1)
				(type default)
			)
			(layer "B.Fab")
		)
		(fp_line
			(start -0.67945 0.3048)
			(end -0.120396 0.3048)
			(stroke
				(width 0.1)
				(type default)
			)
			(layer "B.Fab")
		)
		(fp_line
			(start -0.12065 -0.3048)
			(end -0.67945 -0.3048)
			(stroke
				(width 0.1)
				(type default)
			)
			(layer "B.Fab")
		)
		(fp_line
			(start -0.12065 -0.2794)
			(end -0.12065 -0.3048)
			(stroke
				(width 0.1)
				(type default)
			)
			(layer "B.Fab")
		)
		(fp_line
			(start -0.120396 0.2794)
			(end 0.12065 0.2794)
			(stroke
				(width 0.1)
				(type default)
			)
			(layer "B.Fab")
		)
		(fp_line
			(start -0.120396 0.3048)
			(end -0.120396 0.2794)
			(stroke
				(width 0.1)
				(type default)
			)
			(layer "B.Fab")
		)
		(fp_line
			(start 0.12065 -0.305054)
			(end 0.12065 -0.2794)
			(stroke
				(width 0.1)
				(type default)
			)
			(layer "B.Fab")
		)
		(fp_line
			(start 0.12065 -0.2794)
			(end -0.12065 -0.2794)
			(stroke
				(width 0.1)
				(type default)
			)
			(layer "B.Fab")
		)
		(fp_line
			(start 0.12065 0.2794)
			(end 0.12065 0.3048)
			(stroke
				(width 0.1)
				(type default)
			)
			(layer "B.Fab")
		)
		(fp_line
			(start 0.12065 0.3048)
			(end 0.67945 0.3048)
			(stroke
				(width 0.1)
				(type default)
			)
			(layer "B.Fab")
		)
		(fp_line
			(start 0.67945 -0.305054)
			(end 0.12065 -0.305054)
			(stroke
				(width 0.1)
				(type default)
			)
			(layer "B.Fab")
		)
		(fp_line
			(start 0.67945 0.3048)
			(end 0.67945 -0.305054)
			(stroke
				(width 0.1)
				(type default)
			)
			(layer "B.Fab")
		)
		(pad "1" smd circle
			(at 0.40005 0 180)
			(size 0 0)
			(layers "B.Cu" "B.Mask" "B.Paste")
			(net "PVDDCR_SOC_P1")
		)
		(pad "2" smd circle
			(at -0.40005 0 180)
			(size 0 0)
			(layers "B.Cu" "B.Mask" "B.Paste")
			(net "GND")
		)
	)
	(footprint ""
		(layer "B.Cu")
		(at 451.549516 -10.634726 90)
		(property "Reference" "R8421"
			(at 0 0 90)
			(layer "B.SilkS")
			(hide yes)
			(effects
				(font
					(size 1.27 1.27)
				)
				(justify mirror)
			)
		)
		(property "Value" ""
			(at 0 0 90)
			(layer "B.Fab")
			(effects
				(font
					(size 1.27 1.27)
				)
				(justify mirror)
			)
		)
		(duplicate_pad_numbers_are_jumpers no)
		(fp_line
			(start 0.7874 -0.4064)
			(end -0.7874 -0.4064)
			(stroke
				(width 0.1524)
				(type default)
			)
			(layer "B.SilkS")
		)
		(fp_line
			(start -0.7874 -0.4064)
			(end -0.7874 0.4064)
			(stroke
				(width 0.1524)
				(type default)
			)
			(layer "B.SilkS")
		)
		(fp_line
			(start 0.7874 0.4064)
			(end 0.7874 -0.4064)
			(stroke
				(width 0.1524)
				(type default)
			)
			(layer "B.SilkS")
		)
		(fp_line
			(start -0.7874 0.4064)
			(end 0.7874 0.4064)
			(stroke
				(width 0.1524)
				(type default)
			)
			(layer "B.SilkS")
		)
		(fp_line
			(start 0.67945 -0.305054)
			(end 0.12065 -0.305054)
			(stroke
				(width 0.1)
				(type default)
			)
			(layer "B.Fab")
		)
		(fp_line
			(start 0.12065 -0.305054)
			(end 0.12065 -0.2794)
			(stroke
				(width 0.1)
				(type default)
			)
			(layer "B.Fab")
		)
		(fp_line
			(start -0.12065 -0.3048)
			(end -0.67945 -0.3048)
			(stroke
				(width 0.1)
				(type default)
			)
			(layer "B.Fab")
		)
		(fp_line
			(start -0.67945 -0.3048)
			(end -0.67945 0.3048)
			(stroke
				(width 0.1)
				(type default)
			)
			(layer "B.Fab")
		)
		(fp_line
			(start 0.12065 -0.2794)
			(end -0.12065 -0.2794)
			(stroke
				(width 0.1)
				(type default)
			)
			(layer "B.Fab")
		)
		(fp_line
			(start -0.12065 -0.2794)
			(end -0.12065 -0.3048)
			(stroke
				(width 0.1)
				(type default)
			)
			(layer "B.Fab")
		)
		(fp_line
			(start 0.12065 0.2794)
			(end 0.12065 0.3048)
			(stroke
				(width 0.1)
				(type default)
			)
			(layer "B.Fab")
		)
		(fp_line
			(start -0.120396 0.2794)
			(end 0.12065 0.2794)
			(stroke
				(width 0.1)
				(type default)
			)
			(layer "B.Fab")
		)
		(fp_line
			(start 0.67945 0.3048)
			(end 0.67945 -0.305054)
			(stroke
				(width 0.1)
				(type default)
			)
			(layer "B.Fab")
		)
		(fp_line
			(start 0.12065 0.3048)
			(end 0.67945 0.3048)
			(stroke
				(width 0.1)
				(type default)
			)
			(layer "B.Fab")
		)
		(fp_line
			(start -0.120396 0.3048)
			(end -0.120396 0.2794)
			(stroke
				(width 0.1)
				(type default)
			)
			(layer "B.Fab")
		)
		(fp_line
			(start -0.67945 0.3048)
			(end -0.120396 0.3048)
			(stroke
				(width 0.1)
				(type default)
			)
			(layer "B.Fab")
		)
		(pad "1" smd circle
			(at 0.40005 0 270)
			(size 0 0)
			(layers "B.Cu" "B.Mask" "B.Paste")
			(net "SGPIO_OCP_SFF_DATAIN")
		)
		(pad "2" smd circle
			(at -0.40005 0 270)
			(size 0 0)
			(layers "B.Cu" "B.Mask" "B.Paste")
			(net "P3V3_OCP_SFF")
		)
	)
	(footprint ""
		(layer "B.Cu")
		(at 254.635 -334.01 180)
		(property "Reference" "R1383"
			(at 0 0 0)
			(layer "B.SilkS")
			(hide yes)
			(effects
				(font
					(size 1.27 1.27)
				)
				(justify mirror)
			)
		)
		(property "Value" ""
			(at 0 0 0)
			(layer "B.Fab")
			(effects
				(font
					(size 1.27 1.27)
				)
				(justify mirror)
			)
		)
		(duplicate_pad_numbers_are_jumpers no)
		(fp_line
			(start 0.32512 0.175006)
			(end 0.32512 -0.175006)
			(stroke
				(width 0.1)
				(type default)
			)
			(layer "B.Fab")
		)
		(fp_line
			(start 0.32512 -0.175006)
			(end -0.32512 -0.175006)
			(stroke
				(width 0.1)
				(type default)
			)
			(layer "B.Fab")
		)
		(fp_line
			(start -0.32512 0.175006)
			(end 0.32512 0.175006)
			(stroke
				(width 0.1)
				(type default)
			)
			(layer "B.Fab")
		)
		(fp_line
			(start -0.32512 -0.175006)
			(end -0.32512 0.175006)
			(stroke
				(width 0.1)
				(type default)
			)
			(layer "B.Fab")
		)
		(pad "1" smd rect
			(at 0.2667 0)
			(size 0.3048 0.381)
			(layers "B.Cu" "B.Mask" "B.Paste")
			(net "P1V8_CPU0_RT_1D")
		)
		(pad "2" smd rect
			(at -0.2667 0 180)
			(size 0.3048 0.381)
			(layers "B.Cu" "B.Mask" "B.Paste")
			(net "SMB_RT_CPU0_P2_ROM_MUX_2D_R_SCL")
		)
	)
)
